FILE_TYPE = MACRO_DRAWING;
SET COLOR_WIRE YELLOW;
SET COLOR_PROP MONO;
SET COLOR_DOT WHITE;
SET COLOR_ARC YELLOW;
SET COLOR_BODY GREEN;
SET COLOR_NOTE MONO;
SET PROP_DISPLAY VALUE;
SET PAGE_NUMBER P176;
FORCEADD TPS2061..1
(-1100 1825);
FORCEPROP 1 LAST PART_NUMBER H66405-001
J 0
(-1350 1525);
DISPLAY 0.617021 (-1350 1525);
PAINT BLUE (-1350 1525);
FORCEPROP 2 LASTPIN (-1400 1925) $PN 5
J 2
(-1410 1935);
DISPLAY 0.617021 (-1410 1935);
PAINT ORANGE (-1410 1935);
FORCEPROP 2 LASTPIN (-800 1825) $PN 3
J 0
(-790 1835);
DISPLAY 0.617021 (-790 1835);
PAINT ORANGE (-790 1835);
FORCEPROP 2 LASTPIN (-1400 1725) $PN 4
J 2
(-1410 1735);
DISPLAY 0.617021 (-1410 1735);
PAINT ORANGE (-1410 1735);
FORCEPROP 2 LASTPIN (-800 1925) $PN 1
J 0
(-790 1935);
DISPLAY 0.617021 (-790 1935);
PAINT ORANGE (-790 1935);
FORCEPROP 1 LAST MATERIAL IC
J 0
(-1350 2125);
DISPLAY 0.617021 (-1350 2125);
PAINT SKYBLUE (-1350 2125);
FORCEPROP 1 LAST LOCATION U1M3
J 0
(-1350 2175);
DISPLAY 0.617021 (-1350 2175);
PAINT AQUA (-1350 2175);
FORCEPROP 2 LASTPIN (-800 1625) $PN 2
J 0
(-790 1635);
DISPLAY 0.617021 (-790 1635);
PAINT ORANGE (-790 1635);
FORCEPROP 0 LAST ROOM USB_REAR
J 0
(-1350 2275);
DISPLAY 1.021277 (-1350 2275);
PAINT ORANGE (-1350 2275);
DISPLAY INVISIBLE (-1350 2275);
FORCEPROP 1 LAST PATH I100
J 0
(-1050 2125);
PAINT GREEN (-1050 2125);
DISPLAY INVISIBLE (-1050 2125);
FORCEPROP 2 LAST SEC 1
J 0
(-1350 2225);
DISPLAY 0.680851 (-1350 2225);
PAINT MONO (-1350 2225);
DISPLAY INVISIBLE (-1350 2225);
FORCEPROP 0 LAST BOM_COST MIO_USB
J 0
(-1350 2275);
DISPLAY 1.021277 (-1350 2275);
PAINT ORANGE (-1350 2275);
DISPLAY INVISIBLE (-1350 2275);
FORCEPROP 2 LAST SEC_TYPE SM
J 0
(-1350 2225);
DISPLAY 1.021277 (-1350 2225);
PAINT ORANGE (-1350 2225);
DISPLAY INVISIBLE (-1350 2225);
FORCEPROP 1 LAST PACK_TYPE SM
J 0
(-1350 2225);
PAINT SKYBLUE (-1350 2225);
DISPLAY INVISIBLE (-1350 2225);
FORCEPROP 2 LAST CDS_LIB mstr_vreg
J 0
(-1100 1825);
PAINT MONO (-1100 1825);
DISPLAY INVISIBLE (-1100 1825);
FORCEADD P5V..1
(-1800 2600);
FORCEPROP 3 LASTPIN (-1800 2550) SIG_NAME P5V\g
J 0
(-1790 2560);
DISPLAY 0.659574 (-1790 2560);
PAINT MONO (-1790 2560);
DISPLAY INVISIBLE (-1790 2560);
FORCEPROP 1 LAST PATH I101
J 0
(-1755 2602);
DISPLAY 0.340426 (-1755 2602);
PAINT GREEN (-1755 2602);
DISPLAY INVISIBLE (-1755 2602);
FORCEPROP 2 LAST CDS_LIB mstr_symbols
J 0
(-1800 2600);
PAINT MONO (-1800 2600);
DISPLAY INVISIBLE (-1800 2600);
FORCEPROP 1 LAST SIZE 1B
J 0
(-1755 2622);
DISPLAY 0.340426 (-1755 2622);
PAINT GREEN (-1755 2622);
DISPLAY INVISIBLE (-1755 2622);
FORCEPROP 1 LAST VOLTAGE 5.0V
J 0
(-1845 2557);
DISPLAY 0.340426 (-1845 2557);
PAINT SKYBLUE (-1845 2557);
DISPLAY INVISIBLE (-1845 2557);
FORCEPROP 1 LAST BODY_TYPE PLUMBING
J 0
(-1845 2557);
DISPLAY 0.340426 (-1845 2557);
PAINT GREEN (-1845 2557);
DISPLAY INVISIBLE (-1845 2557);
FORCEPROP 1 LAST HDL_POWER P5V
J 0
(-2100 2475);
DISPLAY 0.872340 (-2100 2475);
PAINT ORANGE (-2100 2475);
DISPLAY INVISIBLE (-2100 2475);
FORCEADD GND..1
(-725 1450);
FORCEPROP 3 LASTPIN (-725 1500) SIG_NAME GND\g
J 0
(-715 1510);
DISPLAY 0.659574 (-715 1510);
PAINT MONO (-715 1510);
DISPLAY INVISIBLE (-715 1510);
FORCEPROP 1 LAST PATH I102
J 0
(-650 1450);
DISPLAY 0.872340 (-650 1450);
PAINT AQUA (-650 1450);
DISPLAY INVISIBLE (-650 1450);
FORCEPROP 1 LAST SIZE 1B
J 0
(-650 1400);
DISPLAY 0.872340 (-650 1400);
PAINT AQUA (-650 1400);
DISPLAY INVISIBLE (-650 1400);
FORCEPROP 1 LAST VOLTAGE 0
J 0
(-725 1450);
PAINT SKYBLUE (-725 1450);
DISPLAY INVISIBLE (-725 1450);
FORCEPROP 1 LAST HDL_POWER GND
J 0
(-725 1600);
DISPLAY 0.872340 (-725 1600);
PAINT GREEN (-725 1600);
DISPLAY INVISIBLE (-725 1600);
FORCEPROP 1 LAST BODY_TYPE PLUMBING
J 0
(-770 1407);
DISPLAY 0.340426 (-770 1407);
PAINT GREEN (-770 1407);
DISPLAY INVISIBLE (-770 1407);
FORCEPROP 2 LAST CDS_LIB mstr_symbols
J 0
(-725 1450);
PAINT ORANGE (-725 1450);
DISPLAY INVISIBLE (-725 1450);
FORCEADD OFFPAGE..2
(25 1925);
FORCEPROP 2 LAST $XR0 176 
J 0
(214 1925);
DISPLAY 0.638298 (214 1925);
PAINT MONO (214 1925);
FORCEPROP 2 LAST CDS_LIB mstr_standard
J 0
(25 1925);
PAINT ORANGE (25 1925);
DISPLAY INVISIBLE (25 1925);
FORCEPROP 2 LAST PATH I103
J 0
(225 1975);
DISPLAY 1.021277 (225 1975);
PAINT ORANGE (225 1975);
DISPLAY INVISIBLE (225 1975);
FORCEPROP 1 LAST OFFPAGE TRUE
J 0
(350 1800);
DISPLAY 0.872340 (350 1800);
PAINT GREEN (350 1800);
DISPLAY INVISIBLE (350 1800);
FORCEPROP 1 LAST COMMENT_BODY TRUE
J 0
(-20 1830);
DISPLAY 0.872340 (-20 1830);
PAINT GREEN (-20 1830);
DISPLAY INVISIBLE (-20 1830);
FORCEADD OFFPAGE..2
(25 1825);
FORCEPROP 2 LAST $XR0 120 
J 0
(214 1825);
DISPLAY 0.638298 (214 1825);
PAINT MONO (214 1825);
FORCEPROP 2 LAST PATH I104
J 0
(225 1875);
DISPLAY 1.021277 (225 1875);
PAINT ORANGE (225 1875);
DISPLAY INVISIBLE (225 1875);
FORCEPROP 1 LAST OFFPAGE TRUE
J 0
(350 1700);
DISPLAY 0.872340 (350 1700);
PAINT GREEN (350 1700);
DISPLAY INVISIBLE (350 1700);
FORCEPROP 1 LAST COMMENT_BODY TRUE
J 0
(-20 1730);
DISPLAY 0.872340 (-20 1730);
PAINT GREEN (-20 1730);
DISPLAY INVISIBLE (-20 1730);
FORCEPROP 2 LAST CDS_LIB mstr_standard
J 0
(25 1825);
PAINT ORANGE (25 1825);
DISPLAY INVISIBLE (25 1825);
FORCEADD RES..2
(-675 2300);
FORCEPROP 1 LAST LOCATION R1M24
J 0
(-630 2425);
DISPLAY 0.617021 (-630 2425);
PAINT AQUA (-630 2425);
FORCEPROP 1 LASTPIN (-675 2400) $PN 1
J 0
(-670 2362);
DISPLAY 0.617021 (-670 2362);
PAINT ORANGE (-670 2362);
FORCEPROP 1 LASTPIN (-675 2200) $PN 2
J 0
(-670 2210);
DISPLAY 0.617021 (-670 2210);
PAINT ORANGE (-670 2210);
FORCEPROP 1 LAST TOLERANCE 1%
J 0
(-630 2325);
DISPLAY 0.617021 (-630 2325);
PAINT SKYBLUE (-630 2325);
FORCEPROP 1 LAST PART_NUMBER G21796-016
J 0
(-635 2175);
DISPLAY 0.617021 (-635 2175);
PAINT BLUE (-635 2175);
FORCEPROP 1 LAST MATERIAL CHIP
J 0
(-635 2225);
DISPLAY 0.617021 (-635 2225);
PAINT SKYBLUE (-635 2225);
FORCEPROP 1 LAST WATTAGE 1/16W
J 0
(-635 2275);
DISPLAY 0.617021 (-635 2275);
PAINT SKYBLUE (-635 2275);
FORCEPROP 1 LAST PACK_TYPE 0402
J 0
(-635 2125);
DISPLAY 0.617021 (-635 2125);
PAINT SKYBLUE (-635 2125);
FORCEPROP 1 LAST VALUE 10.0K
J 0
(-630 2375);
DISPLAY 0.617021 (-630 2375);
PAINT SKYBLUE (-630 2375);
FORCEPROP 0 LAST BOM_COST MIO_USB
J 0
(-625 2525);
DISPLAY 1.021277 (-625 2525);
PAINT ORANGE (-625 2525);
DISPLAY INVISIBLE (-625 2525);
FORCEPROP 2 LAST SEC_TYPE 0402
J 0
(-625 2525);
DISPLAY 1.021277 (-625 2525);
PAINT ORANGE (-625 2525);
DISPLAY INVISIBLE (-625 2525);
FORCEPROP 2 LAST SEC 1
J 0
(-625 2525);
DISPLAY 0.680851 (-625 2525);
PAINT MONO (-625 2525);
DISPLAY INVISIBLE (-625 2525);
FORCEPROP 1 LAST PATH I105
J 0
(-625 2475);
DISPLAY 0.978723 (-625 2475);
PAINT WHITE (-625 2475);
DISPLAY INVISIBLE (-625 2475);
FORCEPROP 2 LAST ROOM USB_REAR
J 0
(-675 2300);
PAINT MONO (-675 2300);
DISPLAY INVISIBLE (-675 2300);
FORCEPROP 2 LAST CDS_LIB mstr_discrete
J 0
(-675 2300);
PAINT MONO (-675 2300);
DISPLAY INVISIBLE (-675 2300);
FORCEADD OFFPAGE..1
(-2600 1725);
FORCEPROP 2 LAST $XR0 119 
J 0
(-2882 1725);
DISPLAY 0.638298 (-2882 1725);
PAINT MONO (-2882 1725);
FORCEPROP 2 LAST $XR1 125 
J 0
(-3002 1725);
DISPLAY 0.638298 (-3002 1725);
PAINT MONO (-3002 1725);
FORCEPROP 2 LAST PATH I107
J 0
(-2550 1800);
DISPLAY 1.021277 (-2550 1800);
PAINT ORANGE (-2550 1800);
DISPLAY INVISIBLE (-2550 1800);
FORCEPROP 1 LAST COMMENT_BODY TRUE
J 0
(-2475 1625);
DISPLAY 0.872340 (-2475 1625);
PAINT GREEN (-2475 1625);
DISPLAY INVISIBLE (-2475 1625);
FORCEPROP 1 LAST OFFPAGE TRUE
J 0
(-2275 1600);
DISPLAY 0.872340 (-2275 1600);
PAINT GREEN (-2275 1600);
DISPLAY INVISIBLE (-2275 1600);
FORCEPROP 2 LAST CDS_LIB mstr_standard
J 0
(-2600 1725);
PAINT MONO (-2600 1725);
DISPLAY INVISIBLE (-2600 1725);
FORCEADD CAP_A..1
(-2075 2250);
FORCEPROP 1 LAST LOCATION C1M38
J 0
(-2025 2350);
DISPLAY 0.617021 (-2025 2350);
PAINT AQUA (-2025 2350);
FORCEPROP 1 LAST PART_NUMBER A36096-030
J 0
(-2025 2100);
DISPLAY 0.617021 (-2025 2100);
PAINT BLUE (-2025 2100);
FORCEPROP 1 LAST PACK_TYPE 0402V
J 0
(-2025 2050);
DISPLAY 0.617021 (-2025 2050);
PAINT SKYBLUE (-2025 2050);
FORCEPROP 1 LAST VALUE 0.1UF
J 0
(-2025 2300);
DISPLAY 0.617021 (-2025 2300);
PAINT SKYBLUE (-2025 2300);
FORCEPROP 1 LASTPIN (-2075 2150) $PN 2
J 0
(-2065 2130);
DISPLAY 0.617021 (-2065 2130);
PAINT ORANGE (-2065 2130);
FORCEPROP 1 LAST VOLTAGE 16V
J 0
(-2025 2250);
DISPLAY 0.617021 (-2025 2250);
PAINT SKYBLUE (-2025 2250);
FORCEPROP 1 LAST MATERIAL X7R
J 0
(-2025 2150);
DISPLAY 0.617021 (-2025 2150);
PAINT SKYBLUE (-2025 2150);
FORCEPROP 1 LASTPIN (-2075 2350) $PN 1
J 0
(-2065 2330);
DISPLAY 0.617021 (-2065 2330);
PAINT ORANGE (-2065 2330);
FORCEPROP 1 LAST TOLERANCE 10%
J 0
(-2025 2200);
DISPLAY 0.617021 (-2025 2200);
PAINT SKYBLUE (-2025 2200);
FORCEPROP 0 LAST BOM_COST MIO_USB
J 0
(-2025 2450);
DISPLAY 1.021277 (-2025 2450);
PAINT ORANGE (-2025 2450);
DISPLAY INVISIBLE (-2025 2450);
FORCEPROP 2 LAST SEC_TYPE 0402V
J 0
(-2025 2450);
DISPLAY 1.021277 (-2025 2450);
PAINT ORANGE (-2025 2450);
DISPLAY INVISIBLE (-2025 2450);
FORCEPROP 2 LAST SEC 1
J 0
(-2025 2450);
PAINT MONO (-2025 2450);
DISPLAY INVISIBLE (-2025 2450);
FORCEPROP 2 LAST CDS_SEC 1
J 0
(-2025 2400);
PAINT ORANGE (-2025 2400);
DISPLAY INVISIBLE (-2025 2400);
FORCEPROP 0 LAST ROOM USB_REAR
J 0
(-2025 2400);
DISPLAY 1.021277 (-2025 2400);
PAINT ORANGE (-2025 2400);
DISPLAY INVISIBLE (-2025 2400);
FORCEPROP 1 LAST PATH I108
J 0
(-2025 2400);
DISPLAY 0.978723 (-2025 2400);
PAINT WHITE (-2025 2400);
DISPLAY INVISIBLE (-2025 2400);
FORCEPROP 2 LAST CDS_LIB dev_discrete
J 0
(-2075 2250);
PAINT ORANGE (-2075 2250);
DISPLAY INVISIBLE (-2075 2250);
FORCEADD GND..1
(-2075 1950);
FORCEPROP 3 LASTPIN (-2075 2000) SIG_NAME GND\g
J 0
(-2065 2010);
DISPLAY 0.659574 (-2065 2010);
PAINT MONO (-2065 2010);
DISPLAY INVISIBLE (-2065 2010);
FORCEPROP 1 LAST PATH I109
J 0
(-2000 1950);
DISPLAY 0.872340 (-2000 1950);
PAINT AQUA (-2000 1950);
DISPLAY INVISIBLE (-2000 1950);
FORCEPROP 1 LAST SIZE 1B
J 0
(-2000 1900);
DISPLAY 0.872340 (-2000 1900);
PAINT AQUA (-2000 1900);
DISPLAY INVISIBLE (-2000 1900);
FORCEPROP 1 LAST VOLTAGE 0
J 0
(-2075 1950);
PAINT SKYBLUE (-2075 1950);
DISPLAY INVISIBLE (-2075 1950);
FORCEPROP 2 LAST CDS_LIB mstr_symbols
J 0
(-2075 1950);
PAINT MONO (-2075 1950);
DISPLAY INVISIBLE (-2075 1950);
FORCEPROP 1 LAST BODY_TYPE PLUMBING
J 0
(-2120 1907);
DISPLAY 0.340426 (-2120 1907);
PAINT GREEN (-2120 1907);
DISPLAY INVISIBLE (-2120 1907);
FORCEPROP 1 LAST HDL_POWER GND
J 0
(-2075 2100);
DISPLAY 0.872340 (-2075 2100);
PAINT GREEN (-2075 2100);
DISPLAY INVISIBLE (-2075 2100);
FORCEADD P3V3_STBY..1
(-675 2575);
FORCEPROP 3 LASTPIN (-675 2525) SIG_NAME P3V3_STBY\g
J 0
(-665 2535);
DISPLAY 0.659574 (-665 2535);
PAINT MONO (-665 2535);
DISPLAY INVISIBLE (-665 2535);
FORCEPROP 1 LAST VOLTAGE 3.3V
J 0
(-720 2532);
DISPLAY 0.340426 (-720 2532);
PAINT SKYBLUE (-720 2532);
DISPLAY INVISIBLE (-720 2532);
FORCEPROP 1 LAST SIZE 1B
J 0
(-630 2597);
DISPLAY 0.340426 (-630 2597);
PAINT GREEN (-630 2597);
DISPLAY INVISIBLE (-630 2597);
FORCEPROP 2 LAST CDS_LIB mstr_symbols
J 0
(-675 2575);
PAINT MONO (-675 2575);
DISPLAY INVISIBLE (-675 2575);
FORCEPROP 1 LAST BODY_TYPE PLUMBING
J 0
(-720 2532);
DISPLAY 0.340426 (-720 2532);
PAINT GREEN (-720 2532);
DISPLAY INVISIBLE (-720 2532);
FORCEPROP 1 LAST PATH I110
J 0
(-630 2577);
DISPLAY 0.340426 (-630 2577);
PAINT GREEN (-630 2577);
DISPLAY INVISIBLE (-630 2577);
FORCEPROP 1 LAST HDL_POWER P3V3_STBY
J 0
(-975 2450);
DISPLAY 0.872340 (-975 2450);
PAINT ORANGE (-975 2450);
DISPLAY INVISIBLE (-975 2450);
FORCEADD RES..2
(-1850 1525);
FORCEPROP 1 LAST LOCATION R1M25
J 0
(-1805 1650);
DISPLAY 0.617021 (-1805 1650);
PAINT AQUA (-1805 1650);
FORCEPROP 1 LAST VALUE 10.0K
J 0
(-1805 1600);
DISPLAY 0.617021 (-1805 1600);
PAINT SKYBLUE (-1805 1600);
FORCEPROP 1 LAST TOLERANCE 1%
J 0
(-1805 1550);
DISPLAY 0.617021 (-1805 1550);
PAINT SKYBLUE (-1805 1550);
FORCEPROP 1 LASTPIN (-1850 1425) $PN 2
J 0
(-1845 1435);
DISPLAY 0.617021 (-1845 1435);
PAINT ORANGE (-1845 1435);
FORCEPROP 1 LAST PACK_TYPE 0402
J 0
(-1810 1350);
DISPLAY 0.617021 (-1810 1350);
PAINT SKYBLUE (-1810 1350);
FORCEPROP 1 LASTPIN (-1850 1625) $PN 1
J 0
(-1845 1587);
DISPLAY 0.617021 (-1845 1587);
PAINT ORANGE (-1845 1587);
FORCEPROP 1 LAST WATTAGE 1/16W
J 0
(-1810 1500);
DISPLAY 0.617021 (-1810 1500);
PAINT SKYBLUE (-1810 1500);
FORCEPROP 1 LAST MATERIAL CHIP
J 0
(-1810 1450);
DISPLAY 0.617021 (-1810 1450);
PAINT SKYBLUE (-1810 1450);
FORCEPROP 1 LAST PART_NUMBER G21796-016
J 0
(-1810 1400);
DISPLAY 0.617021 (-1810 1400);
PAINT BLUE (-1810 1400);
FORCEPROP 0 LAST BOM_COST MIO_USB
J 0
(-1800 1750);
DISPLAY 1.021277 (-1800 1750);
PAINT ORANGE (-1800 1750);
DISPLAY INVISIBLE (-1800 1750);
FORCEPROP 2 LAST SEC_TYPE 0402
J 0
(-1800 1750);
DISPLAY 1.021277 (-1800 1750);
PAINT ORANGE (-1800 1750);
DISPLAY INVISIBLE (-1800 1750);
FORCEPROP 1 LAST PATH I111
J 0
(-1800 1700);
DISPLAY 0.978723 (-1800 1700);
PAINT WHITE (-1800 1700);
DISPLAY INVISIBLE (-1800 1700);
FORCEPROP 2 LAST SEC 1
J 0
(-1800 1750);
DISPLAY 0.680851 (-1800 1750);
PAINT MONO (-1800 1750);
DISPLAY INVISIBLE (-1800 1750);
FORCEPROP 2 LAST CDS_LIB mstr_discrete
J 0
(-1850 1525);
PAINT ORANGE (-1850 1525);
DISPLAY INVISIBLE (-1850 1525);
FORCEPROP 2 LAST ROOM USB_REAR
J 0
(-1850 1525);
PAINT MONO (-1850 1525);
DISPLAY INVISIBLE (-1850 1525);
FORCEADD GND..1
(-1850 1300);
FORCEPROP 3 LASTPIN (-1850 1350) SIG_NAME GND\g
J 0
(-1840 1360);
DISPLAY 0.659574 (-1840 1360);
PAINT MONO (-1840 1360);
DISPLAY INVISIBLE (-1840 1360);
FORCEPROP 1 LAST HDL_POWER GND
J 0
(-1850 1450);
DISPLAY 0.872340 (-1850 1450);
PAINT GREEN (-1850 1450);
DISPLAY INVISIBLE (-1850 1450);
FORCEPROP 1 LAST PATH I112
J 0
(-1775 1300);
DISPLAY 0.872340 (-1775 1300);
PAINT AQUA (-1775 1300);
DISPLAY INVISIBLE (-1775 1300);
FORCEPROP 1 LAST BODY_TYPE PLUMBING
J 0
(-1895 1257);
DISPLAY 0.340426 (-1895 1257);
PAINT GREEN (-1895 1257);
DISPLAY INVISIBLE (-1895 1257);
FORCEPROP 1 LAST SIZE 1B
J 0
(-1775 1250);
DISPLAY 0.872340 (-1775 1250);
PAINT AQUA (-1775 1250);
DISPLAY INVISIBLE (-1775 1250);
FORCEPROP 2 LAST CDS_LIB mstr_symbols
J 0
(-1850 1300);
PAINT ORANGE (-1850 1300);
DISPLAY INVISIBLE (-1850 1300);
FORCEPROP 1 LAST VOLTAGE 0
J 0
(-1850 1300);
PAINT SKYBLUE (-1850 1300);
DISPLAY INVISIBLE (-1850 1300);
FORCEADD CAPP..1
(-525 1625);
FORCEPROP 1 LAST VALUE 330UF
J 0
(-475 1675);
DISPLAY 0.617021 (-475 1675);
PAINT SKYBLUE (-475 1675);
FORCEPROP 1 LASTPIN (-525 1725) $PN 1
J 0
(-515 1710);
DISPLAY 0.617021 (-515 1710);
PAINT ORANGE (-515 1710);
FORCEPROP 1 LAST VOLTAGE 10V
J 0
(-475 1575);
DISPLAY 0.617021 (-475 1575);
PAINT SKYBLUE (-475 1575);
FORCEPROP 1 LAST LOCATION C9B8
J 0
(-475 1725);
DISPLAY 0.617021 (-475 1725);
PAINT AQUA (-475 1725);
FORCEPROP 1 LAST TOLERANCE 20%
J 0
(-475 1625);
DISPLAY 0.617021 (-475 1625);
PAINT SKYBLUE (-475 1625);
FORCEPROP 1 LASTPIN (-525 1525) $PN 2
J 0
(-515 1510);
DISPLAY 0.617021 (-515 1510);
PAINT ORANGE (-515 1510);
FORCEPROP 1 LAST MATERIAL POSCAP
J 0
(-475 1525);
DISPLAY 0.617021 (-475 1525);
PAINT SKYBLUE (-475 1525);
FORCEPROP 1 LAST PACK_TYPE 7343HLF
J 0
(-475 1475);
DISPLAY 0.617021 (-475 1475);
PAINT SKYBLUE (-475 1475);
FORCEPROP 1 LAST PART_NUMBER 724613-043
J 0
(-475 1425);
DISPLAY 0.617021 (-475 1425);
PAINT BLUE (-475 1425);
FORCEPROP 1 LAST PATH I113
J 0
(-475 1775);
DISPLAY 0.978723 (-475 1775);
PAINT ORANGE (-475 1775);
DISPLAY INVISIBLE (-475 1775);
FORCEPROP 2 LAST SEC 1
J 0
(-475 1825);
DISPLAY 0.680851 (-475 1825);
PAINT MONO (-475 1825);
DISPLAY INVISIBLE (-475 1825);
FORCEPROP 2 LAST SEC_TYPE 7343HLF
J 0
(-475 1825);
DISPLAY 1.021277 (-475 1825);
PAINT ORANGE (-475 1825);
DISPLAY INVISIBLE (-475 1825);
FORCEPROP 2 LAST CDS_LIB mstr_discrete
J 0
(-525 1625);
PAINT ORANGE (-525 1625);
DISPLAY INVISIBLE (-525 1625);
FORCEADD GND..1
(-525 1425);
FORCEPROP 3 LASTPIN (-525 1475) SIG_NAME GND\g
J 0
(-515 1485);
DISPLAY 0.659574 (-515 1485);
PAINT MONO (-515 1485);
DISPLAY INVISIBLE (-515 1485);
FORCEPROP 1 LAST HDL_POWER GND
J 0
(-525 1575);
DISPLAY 0.872340 (-525 1575);
PAINT GREEN (-525 1575);
DISPLAY INVISIBLE (-525 1575);
FORCEPROP 1 LAST PATH I114
J 0
(-450 1425);
DISPLAY 0.872340 (-450 1425);
PAINT AQUA (-450 1425);
DISPLAY INVISIBLE (-450 1425);
FORCEPROP 2 LAST CDS_LIB mstr_symbols
J 0
(-525 1425);
PAINT ORANGE (-525 1425);
DISPLAY INVISIBLE (-525 1425);
FORCEPROP 1 LAST VOLTAGE 0
J 0
(-525 1425);
PAINT SKYBLUE (-525 1425);
DISPLAY INVISIBLE (-525 1425);
FORCEPROP 1 LAST SIZE 1B
J 0
(-450 1375);
DISPLAY 0.872340 (-450 1375);
PAINT AQUA (-450 1375);
DISPLAY INVISIBLE (-450 1375);
FORCEPROP 1 LAST BODY_TYPE PLUMBING
J 0
(-570 1382);
DISPLAY 0.340426 (-570 1382);
PAINT GREEN (-570 1382);
DISPLAY INVISIBLE (-570 1382);
FORCEADD OFFPAGE..2
(150 4400);
FORCEPROP 2 LAST $XR1 168 
J 0
(459 4400);
DISPLAY 0.638298 (459 4400);
PAINT MONO (459 4400);
FORCEPROP 2 LAST $XR0 155 
J 0
(339 4400);
DISPLAY 0.638298 (339 4400);
PAINT MONO (339 4400);
FORCEPROP 2 LAST PATH I119
J 0
(325 4475);
DISPLAY 1.021277 (325 4475);
PAINT ORANGE (325 4475);
DISPLAY INVISIBLE (325 4475);
FORCEPROP 1 LAST COMMENT_BODY TRUE
J 0
(105 4305);
DISPLAY 0.872340 (105 4305);
PAINT GREEN (105 4305);
DISPLAY INVISIBLE (105 4305);
FORCEPROP 1 LAST OFFPAGE TRUE
J 0
(475 4275);
DISPLAY 0.872340 (475 4275);
PAINT GREEN (475 4275);
DISPLAY INVISIBLE (475 4275);
FORCEPROP 2 LAST CDS_LIB mstr_standard
J 0
(150 4400);
PAINT MONO (150 4400);
DISPLAY INVISIBLE (150 4400);
FORCEADD OFFPAGE..5
(-2575 4550);
FORCEPROP 2 LAST $XR1 155 
J 0
(-2955 4550);
DISPLAY 0.638298 (-2955 4550);
PAINT MONO (-2955 4550);
FORCEPROP 2 LAST $XR0 158 
J 0
(-2880 4550);
DISPLAY 0.638298 (-2880 4550);
PAINT MONO (-2880 4550);
FORCEPROP 2 LAST $XR2 181 
J 0
(-2805 4550);
DISPLAY 0.638298 (-2805 4550);
PAINT MONO (-2805 4550);
FORCEPROP 2 LAST PATH I120
J 0
(-2525 4625);
DISPLAY 1.021277 (-2525 4625);
PAINT ORANGE (-2525 4625);
DISPLAY INVISIBLE (-2525 4625);
FORCEPROP 2 LAST CDS_LIB mstr_standard
J 0
(-2575 4550);
PAINT MONO (-2575 4550);
DISPLAY INVISIBLE (-2575 4550);
FORCEPROP 1 LAST COMMENT_BODY TRUE
J 0
(-2475 4475);
DISPLAY 0.872340 (-2475 4475);
PAINT PEACH (-2475 4475);
DISPLAY INVISIBLE (-2475 4475);
FORCEPROP 1 LAST OFFPAGE TRUE
J 0
(-2250 4425);
PAINT GREEN (-2250 4425);
DISPLAY INVISIBLE (-2250 4425);
FORCEADD OFFPAGE..1
(-2575 4600);
FORCEPROP 2 LAST PATH I121
J 0
(-2525 4675);
DISPLAY 1.021277 (-2525 4675);
PAINT ORANGE (-2525 4675);
DISPLAY INVISIBLE (-2525 4675);
FORCEPROP 1 LAST OFFPAGE TRUE
J 0
(-2250 4475);
DISPLAY 0.872340 (-2250 4475);
PAINT GREEN (-2250 4475);
DISPLAY INVISIBLE (-2250 4475);
FORCEPROP 1 LAST COMMENT_BODY TRUE
J 0
(-2450 4500);
DISPLAY 0.872340 (-2450 4500);
PAINT GREEN (-2450 4500);
DISPLAY INVISIBLE (-2450 4500);
FORCEPROP 2 LAST CDS_LIB mstr_standard
J 0
(-2575 4600);
PAINT MONO (-2575 4600);
DISPLAY INVISIBLE (-2575 4600);
FORCEPROP 2 LAST $XRERR ?
J 0
(-2971 4600);
DISPLAY 0.638298 (-2971 4600);
PAINT MONO (-2971 4600);
DISPLAY INVISIBLE (-2971 4600);
FORCEPROP 2 LAST $XR0 176 
J 0
(-3001 4600);
DISPLAY 0.638298 (-3001 4600);
PAINT MONO (-3001 4600);
DISPLAY INVISIBLE (-3001 4600);
FORCEADD TTL1G08..1
(-1725 3275);
FORCEPROP 1 LAST MATERIAL IC
J 1
(-1750 3485);
DISPLAY 0.617021 (-1750 3485);
PAINT SKYBLUE (-1750 3485);
FORCEPROP 1 LAST PACK_TYPE SOTLF
J 1
(-1750 3450);
DISPLAY 0.617021 (-1750 3450);
PAINT SKYBLUE (-1750 3450);
FORCEPROP 1 LAST LOCATION U6W10
J 1
(-1750 3410);
DISPLAY 0.617021 (-1750 3410);
PAINT AQUA (-1750 3410);
FORCEPROP 1 LAST PART_NUMBER D10321-001
J 1
(-1750 3375);
DISPLAY 0.617021 (-1750 3375);
PAINT BLUE (-1750 3375);
FORCEPROP 1 LAST VALUE NC7SZ08
J 1
(-1725 3150);
DISPLAY 0.617021 (-1725 3150);
PAINT SKYBLUE (-1725 3150);
FORCEPROP 1 LAST POWER_GROUP VCC=P3V3_STBY;GND=GND;
J 1
(-1700 3100);
DISPLAY 0.617021 (-1700 3100);
PAINT ORANGE (-1700 3100);
FORCEPROP 2 LAST CDS_LIB mstr_ttl
J 0
(-1725 3275);
PAINT MONO (-1725 3275);
DISPLAY INVISIBLE (-1725 3275);
FORCEPROP 0 LAST ROOM CPU_FANS
J 0
(-1750 3575);
DISPLAY 1.021277 (-1750 3575);
PAINT ORANGE (-1750 3575);
DISPLAY INVISIBLE (-1750 3575);
FORCEPROP 0 LAST BOM_COST SM_THERM
J 0
(-1750 3575);
DISPLAY 1.021277 (-1750 3575);
PAINT ORANGE (-1750 3575);
DISPLAY INVISIBLE (-1750 3575);
FORCEPROP 1 LAST PATH I122
J 1
(-1745 3540);
DISPLAY 0.702128 (-1745 3540);
PAINT WHITE (-1745 3540);
DISPLAY INVISIBLE (-1745 3540);
FORCEADD OFFPAGE..2
(-825 3275);
FORCEPROP 2 LAST $XR0 181 
J 0
(-636 3275);
DISPLAY 0.638298 (-636 3275);
PAINT MONO (-636 3275);
FORCEPROP 2 LAST $XR1 158 
J 0
(-636 3275);
DISPLAY 0.638298 (-636 3275);
PAINT MONO (-636 3275);
FORCEPROP 2 LAST PATH I123
J 0
(-625 3325);
DISPLAY 1.021277 (-625 3325);
PAINT ORANGE (-625 3325);
DISPLAY INVISIBLE (-625 3325);
FORCEPROP 2 LAST CDS_LIB mstr_standard
J 0
(-825 3275);
PAINT MONO (-825 3275);
DISPLAY INVISIBLE (-825 3275);
FORCEPROP 1 LAST COMMENT_BODY TRUE
J 0
(-870 3180);
DISPLAY 0.872340 (-870 3180);
PAINT GREEN (-870 3180);
DISPLAY INVISIBLE (-870 3180);
FORCEPROP 1 LAST OFFPAGE TRUE
J 0
(-500 3150);
DISPLAY 0.872340 (-500 3150);
PAINT GREEN (-500 3150);
DISPLAY INVISIBLE (-500 3150);
FORCEADD CAP..1
(-1175 2950);
FORCEPROP 1 LAST PACK_TYPE 0402LF
J 0
(-1125 2750);
DISPLAY 0.617021 (-1125 2750);
PAINT SKYBLUE (-1125 2750);
FORCEPROP 1 LAST PART_NUMBER A36096-030
J 0
(-1125 2800);
DISPLAY 0.617021 (-1125 2800);
PAINT BLUE (-1125 2800);
FORCEPROP 1 LAST MATERIAL X7R
J 0
(-1125 2850);
DISPLAY 0.617021 (-1125 2850);
PAINT SKYBLUE (-1125 2850);
FORCEPROP 1 LAST TOLERANCE 10%
J 0
(-1125 2900);
DISPLAY 0.617021 (-1125 2900);
PAINT SKYBLUE (-1125 2900);
FORCEPROP 1 LAST VOLTAGE 16V
J 0
(-1125 2950);
DISPLAY 0.617021 (-1125 2950);
PAINT SKYBLUE (-1125 2950);
FORCEPROP 1 LAST VALUE 0.1UF
J 0
(-1125 3000);
DISPLAY 0.617021 (-1125 3000);
PAINT SKYBLUE (-1125 3000);
FORCEPROP 1 LAST LOCATION C6W10
J 0
(-1125 3050);
DISPLAY 0.617021 (-1125 3050);
PAINT AQUA (-1125 3050);
FORCEPROP 1 LAST PATH I124
J 0
(-1125 3100);
DISPLAY 0.978723 (-1125 3100);
PAINT WHITE (-1125 3100);
DISPLAY INVISIBLE (-1125 3100);
FORCEPROP 2 LAST CDS_LIB mstr_discrete
J 0
(-1175 2950);
PAINT MONO (-1175 2950);
DISPLAY INVISIBLE (-1175 2950);
FORCEPROP 2 LAST ROOM CPUFANS
J 0
(-1125 3100);
DISPLAY 1.021277 (-1125 3100);
PAINT ORANGE (-1125 3100);
DISPLAY INVISIBLE (-1125 3100);
FORCEPROP 2 LAST BOM_COST SM_THERM
J 0
(-1125 3150);
DISPLAY 1.021277 (-1125 3150);
PAINT ORANGE (-1125 3150);
DISPLAY INVISIBLE (-1125 3150);
FORCEPROP 1 LASTPIN (-1175 2850) $PN 2
J 0
(-1165 2830);
DISPLAY 0.787234 (-1165 2830);
PAINT ORANGE (-1165 2830);
DISPLAY INVISIBLE (-1165 2830);
FORCEPROP 1 LASTPIN (-1175 3050) $PN 1
J 0
(-1165 3030);
DISPLAY 0.787234 (-1165 3030);
PAINT ORANGE (-1165 3030);
DISPLAY INVISIBLE (-1165 3030);
FORCEADD GND..1
(-1175 2750);
FORCEPROP 3 LASTPIN (-1175 2800) SIG_NAME GND\g
J 0
(-1165 2810);
DISPLAY 0.659574 (-1165 2810);
PAINT MONO (-1165 2810);
DISPLAY INVISIBLE (-1165 2810);
FORCEPROP 1 LAST HDL_POWER GND
J 0
(-1175 2900);
DISPLAY 1.170213 (-1175 2900);
PAINT GREEN (-1175 2900);
DISPLAY INVISIBLE (-1175 2900);
FORCEPROP 1 LAST SIZE 1B
J 0
(-1100 2700);
DISPLAY 1.170213 (-1100 2700);
PAINT AQUA (-1100 2700);
DISPLAY INVISIBLE (-1100 2700);
FORCEPROP 2 LAST CDS_LIB mstr_symbols
J 0
(-1175 2750);
PAINT MONO (-1175 2750);
DISPLAY INVISIBLE (-1175 2750);
FORCEPROP 1 LAST BODY_TYPE PLUMBING
J 0
(-1220 2707);
DISPLAY 0.340426 (-1220 2707);
PAINT GREEN (-1220 2707);
DISPLAY INVISIBLE (-1220 2707);
FORCEPROP 1 LAST VOLTAGE 0.0V
J 0
(-1220 2707);
DISPLAY 0.340426 (-1220 2707);
PAINT GREEN (-1220 2707);
DISPLAY INVISIBLE (-1220 2707);
FORCEPROP 1 LAST PATH I125
J 0
(-1100 2750);
DISPLAY 0.872340 (-1100 2750);
PAINT AQUA (-1100 2750);
DISPLAY INVISIBLE (-1100 2750);
FORCEADD P3V3_STBY..1
(-1175 3125);
FORCEPROP 3 LASTPIN (-1175 3075) SIG_NAME P3V3_STBY\g
J 0
(-1165 3085);
DISPLAY 0.659574 (-1165 3085);
PAINT MONO (-1165 3085);
DISPLAY INVISIBLE (-1165 3085);
FORCEPROP 1 LAST SIZE 1B
J 0
(-1130 3147);
DISPLAY 0.340426 (-1130 3147);
PAINT GREEN (-1130 3147);
DISPLAY INVISIBLE (-1130 3147);
FORCEPROP 1 LAST BODY_TYPE PLUMBING
J 0
(-1220 3082);
DISPLAY 0.340426 (-1220 3082);
PAINT GREEN (-1220 3082);
DISPLAY INVISIBLE (-1220 3082);
FORCEPROP 1 LAST HDL_POWER P3V3_STBY
J 0
(-1475 3000);
DISPLAY 0.872340 (-1475 3000);
PAINT ORANGE (-1475 3000);
DISPLAY INVISIBLE (-1475 3000);
FORCEPROP 2 LAST CDS_LIB mstr_symbols
J 0
(-1175 3125);
PAINT MONO (-1175 3125);
DISPLAY INVISIBLE (-1175 3125);
FORCEPROP 1 LAST VOLTAGE 3.3V
J 0
(-1220 3082);
DISPLAY 0.340426 (-1220 3082);
PAINT GREEN (-1220 3082);
DISPLAY INVISIBLE (-1220 3082);
FORCEPROP 1 LAST PATH I126
J 0
(-1130 3127);
DISPLAY 0.340426 (-1130 3127);
PAINT GREEN (-1130 3127);
DISPLAY INVISIBLE (-1130 3127);
FORCEADD OFFPAGE..1
(-2600 3325);
FORCEPROP 2 LAST $XR0 155 
J 0
(-2852 3325);
DISPLAY 0.638298 (-2852 3325);
PAINT MONO (-2852 3325);
FORCEPROP 2 LAST CDS_LIB mstr_standard
J 0
(-2600 3325);
PAINT MONO (-2600 3325);
DISPLAY INVISIBLE (-2600 3325);
FORCEPROP 1 LAST COMMENT_BODY TRUE
J 0
(-2475 3225);
DISPLAY 0.872340 (-2475 3225);
PAINT GREEN (-2475 3225);
DISPLAY INVISIBLE (-2475 3225);
FORCEPROP 1 LAST OFFPAGE TRUE
J 0
(-2275 3200);
DISPLAY 0.872340 (-2275 3200);
PAINT GREEN (-2275 3200);
DISPLAY INVISIBLE (-2275 3200);
FORCEPROP 2 LAST PATH I127
J 0
(-2850 3375);
DISPLAY 1.021277 (-2850 3375);
PAINT ORANGE (-2850 3375);
DISPLAY INVISIBLE (-2850 3375);
FORCEADD OFFPAGE..3
(200 4600);
FORCEPROP 2 LAST $XR1 247 
J 0
(414 4564);
DISPLAY 0.638298 (414 4564);
PAINT MONO (414 4564);
FORCEPROP 2 LAST $XR0 144 
J 0
(414 4600);
DISPLAY 0.638298 (414 4600);
PAINT MONO (414 4600);
FORCEPROP 2 LAST CDS_LIB mstr_standard
J 0
(200 4600);
PAINT MONO (200 4600);
DISPLAY INVISIBLE (200 4600);
FORCEPROP 2 LAST PATH I128
J 0
(400 4675);
DISPLAY 1.021277 (400 4675);
PAINT ORANGE (400 4675);
DISPLAY INVISIBLE (400 4675);
FORCEPROP 1 LAST COMMENT_BODY TRUE
J 0
(150 4500);
DISPLAY 0.872340 (150 4500);
PAINT GREEN (150 4500);
DISPLAY INVISIBLE (150 4500);
FORCEPROP 1 LAST OFFPAGE TRUE
J 0
(525 4475);
DISPLAY 0.872340 (525 4475);
PAINT GREEN (525 4475);
DISPLAY INVISIBLE (525 4475);
FORCEADD OFFPAGE..4
(200 4550);
FORCEPROP 1 LAST COMMENT_BODY TRUE
J 0
(175 4450);
DISPLAY 0.872340 (175 4450);
PAINT GREEN (175 4450);
DISPLAY INVISIBLE (175 4450);
FORCEPROP 1 LAST OFFPAGE TRUE
J 0
(525 4425);
DISPLAY 0.872340 (525 4425);
PAINT GREEN (525 4425);
DISPLAY INVISIBLE (525 4425);
FORCEPROP 2 LAST PATH I129
J 0
(375 4625);
DISPLAY 1.021277 (375 4625);
PAINT ORANGE (375 4625);
DISPLAY INVISIBLE (375 4625);
FORCEPROP 2 LAST CDS_LIB mstr_standard
J 0
(200 4550);
PAINT MONO (200 4550);
DISPLAY INVISIBLE (200 4550);
FORCEPROP 2 LAST $XR1 247 
J 0
(386 4550);
DISPLAY 0.638298 (386 4550);
PAINT MONO (386 4550);
DISPLAY INVISIBLE (386 4550);
FORCEPROP 2 LAST $XR0 144 
J 0
(386 4550);
DISPLAY 0.638298 (386 4550);
PAINT MONO (386 4550);
DISPLAY INVISIBLE (386 4550);
FORCEADD RES..1
(-5300 4375);
FORCEPROP 1 LAST PACK_TYPE 0402
J 0
(-5200 4325);
DISPLAY 0.617021 (-5200 4325);
PAINT SKYBLUE (-5200 4325);
FORCEPROP 1 LAST TOLERANCE 5%
J 0
(-5375 4325);
DISPLAY 0.617021 (-5375 4325);
PAINT SKYBLUE (-5375 4325);
FORCEPROP 1 LAST MATERIAL CHIP
J 0
(-5525 4325);
DISPLAY 0.617021 (-5525 4325);
PAINT SKYBLUE (-5525 4325);
FORCEPROP 1 LASTPIN (-5400 4375) $PN 1
J 0
(-5388 4387);
DISPLAY 0.617021 (-5388 4387);
PAINT WHITE (-5388 4387);
FORCEPROP 1 LAST LOCATION R1M5
J 0
(-5350 4425);
DISPLAY 0.617021 (-5350 4425);
PAINT AQUA (-5350 4425);
FORCEPROP 1 LASTPIN (-5200 4375) $PN 2
J 0
(-5238 4387);
DISPLAY 0.617021 (-5238 4387);
PAINT WHITE (-5238 4387);
FORCEPROP 1 LAST VALUE 0.0
J 2
(-5125 4425);
DISPLAY 0.617021 (-5125 4425);
PAINT SKYBLUE (-5125 4425);
FORCEPROP 1 LAST WATTAGE 1/16W
J 2
(-5325 4250);
DISPLAY 0.510638 (-5325 4250);
PAINT SKYBLUE (-5325 4250);
DISPLAY INVISIBLE (-5325 4250);
FORCEPROP 2 LAST CDS_LOCATION R1M5
J 0
(-5350 4425);
DISPLAY 0.617021 (-5350 4425);
PAINT AQUA (-5350 4425);
DISPLAY INVISIBLE (-5350 4425);
FORCEPROP 1 LAST PATH I16
J 0
(-5350 4525);
DISPLAY 0.978723 (-5350 4525);
PAINT WHITE (-5350 4525);
DISPLAY INVISIBLE (-5350 4525);
FORCEPROP 1 LAST PART_NUMBER G21497-005
J 0
(-5225 4425);
DISPLAY 0.510638 (-5225 4425);
PAINT BLUE (-5225 4425);
DISPLAY INVISIBLE (-5225 4425);
FORCEPROP 2 LAST CDS_LIB mstr_discrete
J 0
(-5300 4375);
PAINT MONO (-5300 4375);
DISPLAY INVISIBLE (-5300 4375);
FORCEPROP 2 LAST SEC_TYPE 0402
J 0
(-5350 4575);
DISPLAY 1.021277 (-5350 4575);
PAINT ORANGE (-5350 4575);
DISPLAY INVISIBLE (-5350 4575);
FORCEPROP 2 LAST SEC 1
J 0
(-5350 4575);
DISPLAY 0.680851 (-5350 4575);
PAINT MONO (-5350 4575);
DISPLAY INVISIBLE (-5350 4575);
FORCEPROP 0 LAST BOM_COST MIO_USB
J 0
(-5125 4525);
DISPLAY 1.021277 (-5125 4525);
PAINT ORANGE (-5125 4525);
DISPLAY INVISIBLE (-5125 4525);
FORCEPROP 0 LAST ROOM USB_REAR
J 0
(-5125 4475);
DISPLAY 1.021277 (-5125 4475);
PAINT ORANGE (-5125 4475);
DISPLAY INVISIBLE (-5125 4475);
FORCEADD CHOKE_4PIN..1
(-5250 4725);
FORCEPROP 1 LAST LOCATION L1M2
J 0
(-5450 5075);
DISPLAY 0.617021 (-5450 5075);
PAINT AQUA (-5450 5075);
FORCEPROP 1 LAST MATERIAL EMPTY
J 0
(-5450 5025);
DISPLAY 0.617021 (-5450 5025);
PAINT RED (-5450 5025);
FORCEPROP 2 LASTPIN (-5500 4625) $PN 2
J 2
(-5510 4635);
DISPLAY 0.617021 (-5510 4635);
PAINT WHITE (-5510 4635);
FORCEPROP 2 LASTPIN (-5500 4825) $PN 1
J 2
(-5510 4835);
DISPLAY 0.617021 (-5510 4835);
PAINT WHITE (-5510 4835);
FORCEPROP 1 LAST PART_NUMBER 752402-015
J 0
(-5475 4510);
DISPLAY 0.617021 (-5475 4510);
PAINT BLUE (-5475 4510);
FORCEPROP 1 LAST VALUE 90 OHM
J 0
(-5450 4975);
DISPLAY 0.617021 (-5450 4975);
PAINT SKYBLUE (-5450 4975);
FORCEPROP 2 LASTPIN (-5050 4625) $PN 3
J 0
(-5040 4635);
DISPLAY 0.617021 (-5040 4635);
PAINT WHITE (-5040 4635);
FORCEPROP 2 LASTPIN (-5050 4825) $PN 4
J 0
(-5040 4835);
DISPLAY 0.617021 (-5040 4835);
PAINT WHITE (-5040 4835);
FORCEPROP 1 LAST PACK_TYPE SMLF
J 0
(-5450 5125);
DISPLAY 0.510638 (-5450 5125);
PAINT SKYBLUE (-5450 5125);
DISPLAY INVISIBLE (-5450 5125);
FORCEPROP 0 LAST BOM_COST MIO_USB
J 0
(-5450 5175);
DISPLAY 1.021277 (-5450 5175);
PAINT ORANGE (-5450 5175);
DISPLAY INVISIBLE (-5450 5175);
FORCEPROP 2 LAST SEC_TYPE SMLF
J 0
(-5450 5125);
DISPLAY 1.021277 (-5450 5125);
PAINT ORANGE (-5450 5125);
DISPLAY INVISIBLE (-5450 5125);
FORCEPROP 2 LAST SEC 1
J 0
(-5450 5125);
DISPLAY 0.680851 (-5450 5125);
PAINT MONO (-5450 5125);
DISPLAY INVISIBLE (-5450 5125);
FORCEPROP 2 LAST CDS_LOCATION L1M2
J 0
(-5450 5075);
DISPLAY 0.617021 (-5450 5075);
PAINT AQUA (-5450 5075);
DISPLAY INVISIBLE (-5450 5075);
FORCEPROP 1 LAST PATH I30
J 2
(-5470 5075);
DISPLAY 0.978723 (-5470 5075);
PAINT WHITE (-5470 5075);
DISPLAY INVISIBLE (-5470 5075);
FORCEPROP 0 LAST ROOM USB_REAR
J 0
(-5450 5125);
DISPLAY 1.021277 (-5450 5125);
PAINT ORANGE (-5450 5125);
DISPLAY INVISIBLE (-5450 5125);
FORCEPROP 2 LAST CDS_LIB mstr_discrete
J 0
(-5250 4725);
PAINT MONO (-5250 4725);
DISPLAY INVISIBLE (-5250 4725);
FORCEADD RES..1
(-5300 5200);
FORCEPROP 1 LAST MATERIAL CHIP
J 0
(-5525 5225);
DISPLAY 0.617021 (-5525 5225);
PAINT SKYBLUE (-5525 5225);
FORCEPROP 1 LASTPIN (-5400 5200) $PN 1
J 0
(-5388 5212);
DISPLAY 0.617021 (-5388 5212);
PAINT WHITE (-5388 5212);
FORCEPROP 1 LAST TOLERANCE 5%
J 0
(-5375 5150);
DISPLAY 0.617021 (-5375 5150);
PAINT SKYBLUE (-5375 5150);
FORCEPROP 1 LAST LOCATION R1M6
J 0
(-5350 5250);
DISPLAY 0.617021 (-5350 5250);
PAINT AQUA (-5350 5250);
FORCEPROP 1 LASTPIN (-5200 5200) $PN 2
J 0
(-5238 5212);
DISPLAY 0.617021 (-5238 5212);
PAINT WHITE (-5238 5212);
FORCEPROP 1 LAST VALUE 0.0
J 2
(-5125 5250);
DISPLAY 0.617021 (-5125 5250);
PAINT SKYBLUE (-5125 5250);
FORCEPROP 1 LAST PACK_TYPE 0402
J 0
(-5200 5150);
DISPLAY 0.617021 (-5200 5150);
PAINT SKYBLUE (-5200 5150);
FORCEPROP 1 LAST WATTAGE 1/16W
J 2
(-5325 5075);
DISPLAY 0.510638 (-5325 5075);
PAINT SKYBLUE (-5325 5075);
DISPLAY INVISIBLE (-5325 5075);
FORCEPROP 2 LAST CDS_LOCATION R1M6
J 0
(-5350 5250);
DISPLAY 0.617021 (-5350 5250);
PAINT AQUA (-5350 5250);
DISPLAY INVISIBLE (-5350 5250);
FORCEPROP 1 LAST PART_NUMBER G21497-005
J 0
(-5225 5250);
DISPLAY 0.510638 (-5225 5250);
PAINT BLUE (-5225 5250);
DISPLAY INVISIBLE (-5225 5250);
FORCEPROP 2 LAST CDS_LIB mstr_discrete
J 0
(-5300 5200);
PAINT MONO (-5300 5200);
DISPLAY INVISIBLE (-5300 5200);
FORCEPROP 0 LAST ROOM USB
J 0
(-5125 5300);
DISPLAY 1.021277 (-5125 5300);
PAINT ORANGE (-5125 5300);
DISPLAY INVISIBLE (-5125 5300);
FORCEPROP 0 LAST BOM_COST MIO_USB
J 0
(-5125 5350);
DISPLAY 1.021277 (-5125 5350);
PAINT ORANGE (-5125 5350);
DISPLAY INVISIBLE (-5125 5350);
FORCEPROP 1 LAST PATH I31
J 0
(-5350 5350);
DISPLAY 0.978723 (-5350 5350);
PAINT WHITE (-5350 5350);
DISPLAY INVISIBLE (-5350 5350);
FORCEPROP 2 LAST SEC_TYPE 0402
J 0
(-5350 5400);
DISPLAY 1.021277 (-5350 5400);
PAINT ORANGE (-5350 5400);
DISPLAY INVISIBLE (-5350 5400);
FORCEPROP 2 LAST SEC 1
J 0
(-5350 5400);
DISPLAY 0.680851 (-5350 5400);
PAINT MONO (-5350 5400);
DISPLAY INVISIBLE (-5350 5400);
FORCEADD OFFPAGE..6
(-7050 4825);
FORCEPROP 2 LAST $XR0 115 
J 0
(-7330 4825);
DISPLAY 0.638298 (-7330 4825);
PAINT MONO (-7330 4825);
FORCEPROP 2 LAST PATH I46
J 0
(-7000 4900);
DISPLAY 1.021277 (-7000 4900);
PAINT ORANGE (-7000 4900);
DISPLAY INVISIBLE (-7000 4900);
FORCEPROP 2 LAST CDS_LIB mstr_standard
J 0
(-7050 4825);
PAINT MONO (-7050 4825);
DISPLAY INVISIBLE (-7050 4825);
FORCEPROP 1 LAST COMMENT_BODY TRUE
J 0
(-6950 4750);
DISPLAY 0.872340 (-6950 4750);
PAINT PEACH (-6950 4750);
DISPLAY INVISIBLE (-6950 4750);
FORCEPROP 1 LAST OFFPAGE TRUE
J 0
(-6725 4700);
PAINT GREEN (-6725 4700);
DISPLAY INVISIBLE (-6725 4700);
FORCEADD OFFPAGE..6
(-7050 4625);
FORCEPROP 2 LAST $XR0 115 
J 0
(-7330 4625);
DISPLAY 0.638298 (-7330 4625);
PAINT MONO (-7330 4625);
FORCEPROP 1 LAST COMMENT_BODY TRUE
J 0
(-6950 4550);
DISPLAY 0.872340 (-6950 4550);
PAINT PEACH (-6950 4550);
DISPLAY INVISIBLE (-6950 4550);
FORCEPROP 1 LAST OFFPAGE TRUE
J 0
(-6725 4500);
PAINT GREEN (-6725 4500);
DISPLAY INVISIBLE (-6725 4500);
FORCEPROP 2 LAST PATH I47
J 0
(-7000 4700);
DISPLAY 1.021277 (-7000 4700);
PAINT ORANGE (-7000 4700);
DISPLAY INVISIBLE (-7000 4700);
FORCEPROP 2 LAST CDS_LIB mstr_standard
J 0
(-7050 4625);
PAINT MONO (-7050 4625);
DISPLAY INVISIBLE (-7050 4625);
FORCEADD CONN9_H51826001..2
(-1300 4550);
FORCEPROP 1 LAST LOCATION J9B1
J 0
(-1850 5000);
DISPLAY 0.617021 (-1850 5000);
PAINT AQUA (-1850 5000);
FORCEPROP 1 LAST MATERIAL CONN
J 0
(-1850 4950);
DISPLAY 0.617021 (-1850 4950);
PAINT SKYBLUE (-1850 4950);
FORCEPROP 2 LASTPIN (-1900 4700) $PN 1
J 2
(-1910 4710);
DISPLAY 0.617021 (-1910 4710);
PAINT MONO (-1910 4710);
FORCEPROP 2 LASTPIN (-1900 4300) $PN MH1
J 2
(-1910 4310);
DISPLAY 0.617021 (-1910 4310);
PAINT MONO (-1910 4310);
FORCEPROP 2 LASTPIN (-1900 4250) $PN MH2
J 2
(-1910 4260);
DISPLAY 0.617021 (-1910 4260);
PAINT MONO (-1910 4260);
FORCEPROP 1 LAST PART_NUMBER H51826-001
J 0
(-1850 4150);
DISPLAY 0.617021 (-1850 4150);
PAINT BLUE (-1850 4150);
FORCEPROP 2 LASTPIN (-650 4550) $PN 5
J 0
(-640 4560);
DISPLAY 0.617021 (-640 4560);
PAINT MONO (-640 4560);
FORCEPROP 2 LASTPIN (-1900 4600) $PN 9
J 2
(-1910 4610);
DISPLAY 0.617021 (-1910 4610);
PAINT MONO (-1910 4610);
FORCEPROP 2 LASTPIN (-1900 4550) $PN 8
J 2
(-1910 4560);
DISPLAY 0.617021 (-1910 4560);
PAINT MONO (-1910 4560);
FORCEPROP 2 LASTPIN (-1900 4400) $PN 2
J 2
(-1910 4410);
DISPLAY 0.617021 (-1910 4410);
PAINT MONO (-1910 4410);
FORCEPROP 2 LASTPIN (-1900 4450) $PN 3
J 2
(-1910 4460);
DISPLAY 0.617021 (-1910 4460);
PAINT MONO (-1910 4460);
FORCEPROP 2 LASTPIN (-650 4450) $PN 4
J 0
(-640 4460);
DISPLAY 0.617021 (-640 4460);
PAINT MONO (-640 4460);
FORCEPROP 2 LASTPIN (-650 4400) $PN 7
J 0
(-640 4410);
DISPLAY 0.617021 (-640 4410);
PAINT MONO (-640 4410);
FORCEPROP 2 LASTPIN (-650 4600) $PN 6
J 0
(-640 4610);
DISPLAY 0.617021 (-640 4610);
PAINT MONO (-640 4610);
FORCEPROP 2 LASTPIN (-650 4300) $PN MH3
J 0
(-640 4310);
DISPLAY 0.617021 (-640 4310);
PAINT MONO (-640 4310);
FORCEPROP 2 LASTPIN (-650 4250) $PN MH4
J 0
(-640 4260);
DISPLAY 0.617021 (-640 4260);
PAINT MONO (-640 4260);
FORCEPROP 2 LAST ROOM USB_REAR
J 0
(-1550 4900);
DISPLAY 1.021277 (-1550 4900);
PAINT ORANGE (-1550 4900);
DISPLAY INVISIBLE (-1550 4900);
FORCEPROP 1 LAST PATH I69
J 0
(-1300 4950);
PAINT GREEN (-1300 4950);
DISPLAY INVISIBLE (-1300 4950);
FORCEPROP 2 LAST CDS_LOCATION J9B1
J 0
(-1850 5000);
DISPLAY 0.617021 (-1850 5000);
PAINT AQUA (-1850 5000);
DISPLAY INVISIBLE (-1850 5000);
FORCEPROP 1 LAST PACK_TYPE PIP2
J 0
(-1850 5050);
PAINT SKYBLUE (-1850 5050);
DISPLAY INVISIBLE (-1850 5050);
FORCEPROP 2 LAST CDS_SEC 1
J 0
(-1850 5050);
PAINT MONO (-1850 5050);
DISPLAY INVISIBLE (-1850 5050);
FORCEPROP 2 LAST $SEC 1
J 0
(-1850 5050);
PAINT MONO (-1850 5050);
DISPLAY INVISIBLE (-1850 5050);
FORCEPROP 2 LAST CDS_LIB mstr_conn
J 0
(-1300 4550);
PAINT ORANGE (-1300 4550);
DISPLAY INVISIBLE (-1300 4550);
FORCEADD GND..1
(-2550 4075);
FORCEPROP 3 LASTPIN (-2550 4125) SIG_NAME GND\g
J 0
(-2540 4135);
DISPLAY 0.659574 (-2540 4135);
PAINT MONO (-2540 4135);
DISPLAY INVISIBLE (-2540 4135);
FORCEPROP 1 LAST VOLTAGE 0.0V
J 0
(-2595 4032);
DISPLAY 0.340426 (-2595 4032);
PAINT SKYBLUE (-2595 4032);
DISPLAY INVISIBLE (-2595 4032);
FORCEPROP 1 LAST SIZE 1B
J 0
(-2475 4025);
DISPLAY 0.872340 (-2475 4025);
PAINT AQUA (-2475 4025);
DISPLAY INVISIBLE (-2475 4025);
FORCEPROP 1 LAST BODY_TYPE PLUMBING
J 0
(-2595 4032);
DISPLAY 0.340426 (-2595 4032);
PAINT GREEN (-2595 4032);
DISPLAY INVISIBLE (-2595 4032);
FORCEPROP 2 LAST CDS_LIB mstr_symbols
J 0
(-2550 4075);
PAINT ORANGE (-2550 4075);
DISPLAY INVISIBLE (-2550 4075);
FORCEPROP 1 LAST PATH I70
J 0
(-2475 4075);
DISPLAY 0.872340 (-2475 4075);
PAINT AQUA (-2475 4075);
DISPLAY INVISIBLE (-2475 4075);
FORCEPROP 1 LAST HDL_POWER GND
J 0
(-2550 4225);
DISPLAY 0.702128 (-2550 4225);
PAINT GREEN (-2550 4225);
DISPLAY INVISIBLE (-2550 4225);
FORCEADD GND..1
(-50 4100);
FORCEPROP 3 LASTPIN (-50 4150) SIG_NAME GND\g
J 0
(-40 4160);
DISPLAY 0.659574 (-40 4160);
PAINT MONO (-40 4160);
DISPLAY INVISIBLE (-40 4160);
FORCEPROP 1 LAST VOLTAGE 0.0V
J 0
(-95 4057);
DISPLAY 0.340426 (-95 4057);
PAINT SKYBLUE (-95 4057);
DISPLAY INVISIBLE (-95 4057);
FORCEPROP 1 LAST BODY_TYPE PLUMBING
J 0
(-95 4057);
DISPLAY 0.340426 (-95 4057);
PAINT GREEN (-95 4057);
DISPLAY INVISIBLE (-95 4057);
FORCEPROP 1 LAST SIZE 1B
J 0
(25 4050);
DISPLAY 0.872340 (25 4050);
PAINT AQUA (25 4050);
DISPLAY INVISIBLE (25 4050);
FORCEPROP 1 LAST PATH I71
J 0
(25 4100);
DISPLAY 0.872340 (25 4100);
PAINT AQUA (25 4100);
DISPLAY INVISIBLE (25 4100);
FORCEPROP 2 LAST CDS_LIB mstr_symbols
J 0
(-50 4100);
PAINT ORANGE (-50 4100);
DISPLAY INVISIBLE (-50 4100);
FORCEPROP 1 LAST HDL_POWER GND
J 0
(-50 4250);
DISPLAY 0.702128 (-50 4250);
PAINT GREEN (-50 4250);
DISPLAY INVISIBLE (-50 4250);
FORCEADD OFFPAGE..1
(-3600 5125);
FORCEPROP 2 LAST $XR0 176 
J 0
(-3852 5125);
DISPLAY 0.638298 (-3852 5125);
PAINT MONO (-3852 5125);
FORCEPROP 2 LAST CDS_LIB mstr_standard
J 0
(-3600 5125);
PAINT ORANGE (-3600 5125);
DISPLAY INVISIBLE (-3600 5125);
FORCEPROP 1 LAST COMMENT_BODY TRUE
J 0
(-3475 5025);
DISPLAY 0.872340 (-3475 5025);
PAINT GREEN (-3475 5025);
DISPLAY INVISIBLE (-3475 5025);
FORCEPROP 2 LAST PATH I75
J 0
(-3550 5200);
DISPLAY 1.021277 (-3550 5200);
PAINT ORANGE (-3550 5200);
DISPLAY INVISIBLE (-3550 5200);
FORCEPROP 1 LAST OFFPAGE TRUE
J 0
(-3275 5000);
DISPLAY 0.872340 (-3275 5000);
PAINT GREEN (-3275 5000);
DISPLAY INVISIBLE (-3275 5000);
FORCEADD DIODEAC_DUAL_ARRAY..7
(-3950 4100);
FORCEPROP 1 LAST MATERIAL IC
J 0
(-4250 4400);
DISPLAY 0.617021 (-4250 4400);
PAINT SKYBLUE (-4250 4400);
FORCEPROP 2 LASTPIN (-3600 4150) $PN 7
J 0
(-3590 4160);
DISPLAY 0.617021 (-3590 4160);
PAINT ORANGE (-3590 4160);
FORCEPROP 1 LAST PART_NUMBER G18435-001
J 0
(-4250 3800);
DISPLAY 0.617021 (-4250 3800);
PAINT BLUE (-4250 3800);
FORCEPROP 2 LASTPIN (-4300 4100) $PN 2
J 2
(-4310 4110);
DISPLAY 0.617021 (-4310 4110);
PAINT ORANGE (-4310 4110);
FORCEPROP 2 LASTPIN (-4300 4050) $PN 1
J 2
(-4310 4060);
DISPLAY 0.617021 (-4310 4060);
PAINT ORANGE (-4310 4060);
FORCEPROP 2 LASTPIN (-4300 4150) $PN 4
J 2
(-4310 4160);
DISPLAY 0.617021 (-4310 4160);
PAINT ORANGE (-4310 4160);
FORCEPROP 2 LASTPIN (-4300 4200) $PN 5
J 2
(-4310 4210);
DISPLAY 0.617021 (-4310 4210);
PAINT ORANGE (-4310 4210);
FORCEPROP 1 LAST LOCATION CR1M2
J 0
(-4250 4450);
DISPLAY 0.617021 (-4250 4450);
PAINT AQUA (-4250 4450);
FORCEPROP 2 LASTPIN (-3600 4200) $PN 6
J 0
(-3590 4210);
DISPLAY 0.617021 (-3590 4210);
PAINT ORANGE (-3590 4210);
FORCEPROP 2 LASTPIN (-3600 4100) $PN 8
J 0
(-3590 4110);
DISPLAY 0.617021 (-3590 4110);
PAINT ORANGE (-3590 4110);
FORCEPROP 2 LASTPIN (-3600 4050) $PN 9
J 0
(-3590 4060);
DISPLAY 0.617021 (-3590 4060);
PAINT ORANGE (-3590 4060);
FORCEPROP 2 LASTPIN (-3600 3950) $PN 3
J 0
(-3590 3960);
DISPLAY 0.617021 (-3590 3960);
PAINT ORANGE (-3590 3960);
FORCEPROP 1 LAST VALUE ESD3V3U4ULC
J 1
(-3975 4275);
DISPLAY 0.617021 (-3975 4275);
PAINT SKYBLUE (-3975 4275);
FORCEPROP 0 LAST BOM_COST MIO_USB
J 0
(-4200 4500);
DISPLAY 1.021277 (-4200 4500);
PAINT ORANGE (-4200 4500);
DISPLAY INVISIBLE (-4200 4500);
FORCEPROP 1 LAST PACK_TYPE SM9
J 0
(-4250 4500);
PAINT SKYBLUE (-4250 4500);
DISPLAY INVISIBLE (-4250 4500);
FORCEPROP 2 LAST SEC_TYPE SM9
J 0
(-4250 4500);
DISPLAY 1.021277 (-4250 4500);
PAINT ORANGE (-4250 4500);
DISPLAY INVISIBLE (-4250 4500);
FORCEPROP 2 LAST SEC 1
J 0
(-4250 4500);
DISPLAY 0.680851 (-4250 4500);
PAINT MONO (-4250 4500);
DISPLAY INVISIBLE (-4250 4500);
FORCEPROP 2 LAST CDS_LOCATION CR1M2
J 0
(-4250 4450);
DISPLAY 0.617021 (-4250 4450);
PAINT AQUA (-4250 4450);
DISPLAY INVISIBLE (-4250 4450);
FORCEPROP 0 LAST ROOM USB_REAR
J 0
(-4200 4450);
DISPLAY 1.021277 (-4200 4450);
PAINT ORANGE (-4200 4450);
DISPLAY INVISIBLE (-4200 4450);
FORCEPROP 2 LAST CDS_LIB mstr_discrete
J 0
(-3950 4100);
PAINT MONO (-3950 4100);
DISPLAY INVISIBLE (-3950 4100);
FORCEPROP 1 LAST PATH I98
J 0
(-3950 4400);
PAINT GREEN (-3950 4400);
DISPLAY INVISIBLE (-3950 4400);
FORCEADD GND..1
(-3300 3725);
FORCEPROP 3 LASTPIN (-3300 3775) SIG_NAME GND\g
J 0
(-3290 3785);
DISPLAY 0.659574 (-3290 3785);
PAINT MONO (-3290 3785);
DISPLAY INVISIBLE (-3290 3785);
FORCEPROP 1 LAST PATH I99
J 0
(-3225 3725);
DISPLAY 0.872340 (-3225 3725);
PAINT AQUA (-3225 3725);
DISPLAY INVISIBLE (-3225 3725);
FORCEPROP 1 LAST BODY_TYPE PLUMBING
J 0
(-3345 3682);
DISPLAY 0.340426 (-3345 3682);
PAINT GREEN (-3345 3682);
DISPLAY INVISIBLE (-3345 3682);
FORCEPROP 2 LAST CDS_LIB mstr_symbols
J 0
(-3300 3725);
PAINT MONO (-3300 3725);
DISPLAY INVISIBLE (-3300 3725);
FORCEPROP 1 LAST SIZE 1B
J 0
(-3225 3675);
DISPLAY 0.872340 (-3225 3675);
PAINT AQUA (-3225 3675);
DISPLAY INVISIBLE (-3225 3675);
FORCEPROP 1 LAST VOLTAGE 0.0V
J 0
(-3345 3682);
DISPLAY 0.340426 (-3345 3682);
PAINT SKYBLUE (-3345 3682);
DISPLAY INVISIBLE (-3345 3682);
FORCEPROP 1 LAST HDL_POWER GND
J 0
(-3300 3875);
DISPLAY 0.872340 (-3300 3875);
PAINT GREEN (-3300 3875);
DISPLAY INVISIBLE (-3300 3875);
FORCEADD CAD_NOTE..1
(-750 2950);
FORCEPROP 0 LAST L1 PLACE CAP CLOSE
J 0
(-900 2825);
DISPLAY 0.617021 (-900 2825);
PAINT WHITE (-900 2825);
FORCEPROP 0 LAST L2 TO IC
J 0
(-900 2750);
DISPLAY 0.617021 (-900 2750);
PAINT WHITE (-900 2750);
FORCEPROP 1 LAST COMMENT_BODY TRUE
J 0
(-725 3050);
DISPLAY 1.361702 (-725 3050);
PAINT WHITE (-725 3050);
DISPLAY INVISIBLE (-725 3050);
FORCEPROP 2 LAST CDS_LIB mstr_symbols
J 0
(-750 2950);
PAINT MONO (-750 2950);
DISPLAY INVISIBLE (-750 2950);
FORCEADD CAD_NOTE..1
(-1250 1375);
FORCEPROP 0 LAST L1 PLACE AS CLOSE AS POSSIBLE TO USB CONNECTOR
J 0
(-1400 1250);
DISPLAY 0.765957 (-1400 1250);
PAINT WHITE (-1400 1250);
FORCEPROP 1 LAST COMMENT_BODY TRUE
J 0
(-1225 1475);
DISPLAY 1.319149 (-1225 1475);
PAINT PEACH (-1225 1475);
DISPLAY INVISIBLE (-1225 1475);
FORCEPROP 2 LAST CDS_LIB mstr_symbols
J 0
(-1250 1375);
PAINT ORANGE (-1250 1375);
DISPLAY INVISIBLE (-1250 1375);
FORCEPROP 2 LAST ROOM ST_SATA
J 0
(-1400 1325);
PAINT WHITE (-1400 1325);
DISPLAY INVISIBLE (-1400 1325);
FORCEPROP 2 LAST BOM_COST MIO_CHASSIS
J 0
(-1400 1325);
PAINT WHITE (-1400 1325);
DISPLAY INVISIBLE (-1400 1325);
FORCEADD DNS..4
(-5245 4720);
PAINT RED (-5245 4720);
FORCEPROP 1 LAST COMMENT_BODY TRUE
R 1
J 0
(-5170 4495);
DISPLAY 0.872340 (-5170 4495);
PAINT GREEN (-5170 4495);
DISPLAY INVISIBLE (-5170 4495);
FORCEPROP 2 LAST CDS_LIB mstr_misc
J 0
(-5245 4720);
PAINT ORANGE (-5245 4720);
DISPLAY INVISIBLE (-5245 4720);
FORCEADD CAD_NOTE..1
(-5425 5400);
FORCEPROP 0 LAST L1 OVERLAPPING FOOTPRINT
J 0
(-5575 5300);
DISPLAY 0.617021 (-5575 5300);
PAINT WHITE (-5575 5300);
FORCEPROP 2 LAST BOM_COST MIO_CHASSIS
J 0
(-5575 5350);
PAINT WHITE (-5575 5350);
DISPLAY INVISIBLE (-5575 5350);
FORCEPROP 2 LAST ROOM ST_SATA
J 0
(-5575 5350);
PAINT WHITE (-5575 5350);
DISPLAY INVISIBLE (-5575 5350);
FORCEPROP 2 LAST CDS_LIB mstr_symbols
J 0
(-5425 5400);
PAINT MONO (-5425 5400);
DISPLAY INVISIBLE (-5425 5400);
FORCEPROP 1 LAST COMMENT_BODY TRUE
J 0
(-5400 5500);
DISPLAY 1.319149 (-5400 5500);
PAINT PEACH (-5400 5500);
DISPLAY INVISIBLE (-5400 5500);
FORCEADD DESIGN_NOTE..1
(-6700 1650);
FORCEPROP 0 LAST L1 TPS2061
J 0
(-6900 1500);
DISPLAY 1.021277 (-6900 1500);
PAINT ORANGE (-6900 1500);
FORCEPROP 0 LAST L2 SHORT-CIRCUIT OUTPUT CURRENT 1.1A MIN - 1.9A MAX
J 0
(-6900 1425);
DISPLAY 1.021277 (-6900 1425);
PAINT ORANGE (-6900 1425);
FORCEPROP 1 LAST COMMENT_BODY TRUE
J 0
(-6675 1750);
DISPLAY 0.978723 (-6675 1750);
PAINT ORANGE (-6675 1750);
DISPLAY INVISIBLE (-6675 1750);
FORCEPROP 2 LAST CDS_LIB mstr_symbols
J 0
(-6700 1650);
PAINT ORANGE (-6700 1650);
DISPLAY INVISIBLE (-6700 1650);
FORCEADD INTEL_CORP_BPAGE..1
(675 800);
FORCEPROP 1 LAST CDS_CON_LAST_MODIFIED Tue Dec 01 11:52:14 2015
J 0
(-750 1125);
PAINT ORANGE (-750 1125);
DISPLAY INVISIBLE (-750 1125);
FORCEPROP 1 LAST CUSTOM_TXT_CDS <CURRENT_DESIGN_SHEET> OF <TOTAL_DESIGN_SHEETS>
J 0
(175 825);
PAINT GREEN (175 825);
FORCEPROP 1 LAST CUSTOM_TXT_CDS <CON_LAST_MODIFIED>
J 0
(-1250 1150);
PAINT GREEN (-1250 1150);
FORCEPROP 2 LAST CUSTOM_TXT_CDS <XR_PAGE_TITLE>
J 0
(-7215 6050);
DISPLAY 0.638298 (-7215 6050);
PAINT PINK (-7215 6050);
DISPLAY INVISIBLE (-7215 6050);
FORCEPROP 1 LAST SCH_NUMBER H4694802
J 0
(-625 950);
DISPLAY 1.212766 (-625 950);
PAINT YELLOW (-625 950);
FORCEPROP 1 LAST SCH_TITLE USB3 EXTERNAL RIGHT ANGLE CONNECTOR
J 0
(-7275 850);
DISPLAY 1.212766 (-7275 850);
PAINT YELLOW (-7275 850);
FORCEPROP 1 LAST SCH_ADDRESS2 P.O. BOX 58119
J 0
(-3300 875);
DISPLAY 0.617021 (-3300 875);
PAINT YELLOW (-3300 875);
FORCEPROP 1 LAST SCH_DEPT BESD
J 1
(-3775 900);
DISPLAY 1.212766 (-3775 900);
PAINT YELLOW (-3775 900);
FORCEPROP 1 LAST SCH_REV 2.420
J 0
(425 950);
DISPLAY 0.978723 (425 950);
PAINT YELLOW (425 950);
FORCEPROP 1 LAST SCH_ADDRESS3 Santa Clara, CA 95052-8119
J 0
(-3300 825);
DISPLAY 0.617021 (-3300 825);
PAINT YELLOW (-3300 825);
FORCEPROP 1 LAST SCH_ADDRESS1 2200 Mission College Blvd.
J 0
(-3300 925);
DISPLAY 0.617021 (-3300 925);
PAINT YELLOW (-3300 925);
FORCEPROP 1 LAST COMMENT_BODY TRUE
J 0
(687 812);
DISPLAY 0.468085 (687 812);
PAINT PEACH (687 812);
DISPLAY INVISIBLE (687 812);
FORCEPROP 2 LAST CDS_LIB mstr_symbols
J 0
(675 800);
PAINT MONO (675 800);
DISPLAY INVISIBLE (675 800);
FORCEPROP 2 LAST PAGE_BORDER TRUE
J 0
(-7215 6050);
DISPLAY 0.638298 (-7215 6050);
PAINT PINK (-7215 6050);
DISPLAY INVISIBLE (-7215 6050);
FORCEPROP 2 LAST CDS_XR_PAGE_TITLE CR-176 : @BASEBOARD_FAB2_LIB.BASEBOARD_FAB2(SCH_1):PAGE176
J 0
(-7215 6050);
DISPLAY 0.638298 (-7215 6050);
PAINT PINK (-7215 6050);
DISPLAY INVISIBLE (-7215 6050);
WIRE 16 -1 (-1400 1925)(-1800 1925);
WIRE 16 -1 (-1800 1925)(-1800 2450);
WIRE 16 -1 (-2075 2450)(-1800 2450);
WIRE 16 -1 (-1800 2450)(-1800 2550);
WIRE 16 -1 (-2075 2350)(-2075 2450);
WIRE 16 -1 (-800 1625)(-725 1625);
WIRE 16 -1 (-725 1625)(-725 1500);
WIRE 16 -1 (-2075 2150)(-2075 2000);
WIRE 16 -1 (-675 2400)(-675 2525);
WIRE 16 -1 (-1850 1425)(-1850 1350);
WIRE 16 -1 (-525 1525)(-525 1475);
WIRE 16 -1 (-1175 2850)(-1175 2800);
WIRE 16 -1 (-1175 3075)(-1175 3050);
WIRE 16 -1 (-2550 4300)(-1900 4300);
WIRE 16 -1 (-2550 4250)(-2550 4300);
WIRE 16 -1 (-1900 4250)(-2550 4250);
WIRE 16 -1 (-2550 4125)(-2550 4250);
WIRE 16 -1 (-50 4300)(-50 4450);
WIRE 16 -1 (-50 4250)(-50 4300);
WIRE 16 -1 (-50 4300)(-650 4300);
WIRE 16 -1 (-50 4450)(-650 4450);
WIRE 16 -1 (-650 4250)(-50 4250);
WIRE 16 -1 (-50 4150)(-50 4250);
WIRE 16 -1 (-3600 3950)(-3300 3950);
WIRE 16 -1 (-3300 3950)(-3300 3775);
WIRE 16 -1 (-1575 3275)(-875 3275);
FORCEPROP 2 LAST SIG_NAME SPA_MID_DBG_RX
J 0
(-1435 3310);
DISPLAY 0.680851 (-1435 3310);
PAINT ORANGE (-1435 3310);
WIRE 3 2175 (575 2725)(575 5400);
WIRE 3 2175 (-3125 2725)(575 2725);
WIRE 3 2175 (575 5400)(-3125 5400);
WIRE 3 2175 (-3125 5400)(-3125 2725);
WIRE 16 -1 (150 4550)(-650 4550);
FORCEPROP 2 LAST SIG_NAME SMB_IPMB_3V3AUX_SCL
J 0
(-535 4560);
DISPLAY 0.680851 (-535 4560);
PAINT ORANGE (-535 4560);
WIRE 16 -1 (150 4600)(-650 4600);
FORCEPROP 2 LAST SIG_NAME SMB_IPMB_3V3AUX_SDA
J 0
(-535 4610);
DISPLAY 0.680851 (-535 4610);
PAINT ORANGE (-535 4610);
WIRE 16 -1 (-650 4400)(100 4400);
FORCEPROP 2 LAST SIG_NAME FM_UART_SWITCH_N
J 0
(-510 4410);
DISPLAY 0.680851 (-510 4410);
PAINT ORANGE (-510 4410);
WIRE 16 -1 (-1875 3325)(-2550 3325);
FORCEPROP 2 LAST SIG_NAME SPA_MID_DBG1__RX
J 0
(-2335 3335);
DISPLAY 0.617021 (-2335 3335);
PAINT ORANGE (-2335 3335);
WIRE 16 -1 (-1875 3225)(-2350 3225);
FORCEPROP 2 LAST SIG_NAME SPA_MID_DBG2_RX
J 0
(-2335 3235);
DISPLAY 0.617021 (-2335 3235);
PAINT ORANGE (-2335 3235);
FORCEPROP 2 LASTPROP $XR0 176 
J 0
(-2446 3225);
DISPLAY 0.638298 (-2446 3225);
PAINT MONO (-2446 3225);
WIRE 2 3135 (-3250 1975)(-3250 3425);
WIRE 2 3135 (-6625 1975)(-3250 1975);
WIRE 2 3135 (-3250 3425)(-6625 3425);
WIRE 2 3135 (-6625 3425)(-6625 1975);
WIRE 16 -1 (-3600 4100)(-2950 4100);
WIRE 16 -1 (-2950 4100)(-2950 4400);
WIRE 16 -1 (-2950 4400)(-1900 4400);
WIRE 16 -1 (-2950 4825)(-2950 4400);
WIRE 16 -1 (-2950 4825)(-4825 4825);
FORCEPROP 2 LAST SIG_NAME USB2_P01_ESD_DN
J 1
(-4235 4835);
DISPLAY 0.617021 (-4235 4835);
PAINT ORANGE (-4235 4835);
FORCEPROP 2 LASTPROP $XRERR UNIQUE?
J 0
(-4475 4835);
DISPLAY 0.638298 (-4475 4835);
PAINT MONO (-4475 4835);
DISPLAY INVISIBLE (-4475 4835);
WIRE 16 -1 (-5000 4825)(-4825 4825);
WIRE 16 -1 (-4825 4100)(-4825 4825);
WIRE 16 -1 (-4825 4100)(-4300 4100);
WIRE 16 -1 (-5000 5200)(-5000 4825);
WIRE 16 -1 (-5050 4825)(-5000 4825);
WIRE 16 -1 (-5200 5200)(-5000 5200);
WIRE 16 -1 (-3600 4050)(-3050 4050);
WIRE 16 -1 (-3050 4050)(-3050 4450);
WIRE 16 -1 (-3050 4450)(-1900 4450);
WIRE 16 -1 (-3050 4625)(-3050 4450);
WIRE 16 -1 (-3050 4625)(-4875 4625);
FORCEPROP 2 LAST SIG_NAME USB2_P01_ESD_DP
J 1
(-4235 4635);
DISPLAY 0.617021 (-4235 4635);
PAINT ORANGE (-4235 4635);
FORCEPROP 2 LASTPROP $XRERR UNIQUE?
J 0
(-4475 4635);
DISPLAY 0.638298 (-4475 4635);
PAINT MONO (-4475 4635);
DISPLAY INVISIBLE (-4475 4635);
WIRE 16 -1 (-5000 4625)(-4875 4625);
WIRE 16 -1 (-4875 4625)(-4875 4050);
WIRE 16 -1 (-4300 4050)(-4875 4050);
WIRE 16 -1 (-5050 4625)(-5000 4625);
WIRE 16 -1 (-5000 4625)(-5000 4375);
WIRE 16 -1 (-5000 4375)(-5200 4375);
WIRE 16 -1 (-3200 4150)(-3600 4150);
FORCEPROP 2 LAST SIG_NAME TP_USB_ESD_OUT2
J 0
(-3535 4160);
DISPLAY 0.617021 (-3535 4160);
PAINT ORANGE (-3535 4160);
FORCEPROP 2 LASTPROP $XRERR UNIQUE?
J 0
(-3070 4160);
DISPLAY 0.638298 (-3070 4160);
PAINT MONO (-3070 4160);
DISPLAY INVISIBLE (-3070 4160);
WIRE 16 -1 (-3175 4200)(-3600 4200);
FORCEPROP 2 LAST SIG_NAME TP_USB_ESD_OUT3
J 0
(-3535 4210);
DISPLAY 0.617021 (-3535 4210);
PAINT ORANGE (-3535 4210);
FORCEPROP 2 LASTPROP $XRERR UNIQUE?
J 0
(-3070 4210);
DISPLAY 0.638298 (-3070 4210);
PAINT MONO (-3070 4210);
DISPLAY INVISIBLE (-3070 4210);
WIRE 16 -1 (-3550 5125)(-2600 5125);
FORCEPROP 0 LAST VOLTAGE 5V
J 0
(-3525 5200);
DISPLAY 1.021277 (-3525 5200);
PAINT SKYBLUE (-3525 5200);
DISPLAY INVISIBLE (-3525 5200);
FORCEPROP 0 LAST SIG_NAME P5V_USB
J 0
(-3535 5135);
DISPLAY 0.617021 (-3535 5135);
PAINT ORANGE (-3535 5135);
WIRE 16 -1 (-2600 5125)(-2600 4700);
WIRE 16 -1 (-2600 4700)(-1900 4700);
WIRE 16 -1 (-7000 4625)(-5550 4625);
FORCEPROP 2 LAST SIG_NAME USB2_P01_DP
J 2
(-6685 4635);
DISPLAY 0.617021 (-6685 4635);
PAINT ORANGE (-6685 4635);
WIRE 16 -1 (-5550 4625)(-5500 4625);
WIRE 16 -1 (-5550 4375)(-5550 4625);
WIRE 16 -1 (-5550 4375)(-5400 4375);
WIRE 16 -1 (-7000 4825)(-5550 4825);
FORCEPROP 2 LAST SIG_NAME USB2_P01_DN
J 2
(-6685 4835);
DISPLAY 0.617021 (-6685 4835);
PAINT ORANGE (-6685 4835);
WIRE 16 -1 (-5550 5200)(-5550 4825);
WIRE 16 -1 (-5550 4825)(-5500 4825);
WIRE 16 -1 (-5400 5200)(-5550 5200);
WIRE 16 -1 (-2550 1725)(-1850 1725);
FORCEPROP 0 LAST SIG_NAME FM_USB_P0_EN_BOOT_BIOS_STRAP_N
J 0
(-2510 1735);
DISPLAY 0.617021 (-2510 1735);
PAINT ORANGE (-2510 1735);
WIRE 16 -1 (-1850 1725)(-1400 1725);
WIRE 16 -1 (-1850 1625)(-1850 1725);
WIRE 16 -1 (-2525 4600)(-1900 4600);
FORCEPROP 2 LAST SIG_NAME SPA_MID_DBG2_RX
J 0
(-2460 4610);
DISPLAY 0.617021 (-2460 4610);
PAINT ORANGE (-2460 4610);
WIRE 16 -1 (-2525 4550)(-1900 4550);
FORCEPROP 2 LAST SIG_NAME SPA_MID_DBG_TX
J 0
(-2485 4560);
DISPLAY 0.680851 (-2485 4560);
PAINT ORANGE (-2485 4560);
WIRE 16 -1 (-525 1725)(-525 1925);
WIRE 16 -1 (-525 1925)(-25 1925);
FORCEPROP 0 LAST SIG_NAME P5V_USB
J 0
(-410 1935);
DISPLAY 0.617021 (-410 1935);
PAINT ORANGE (-410 1935);
WIRE 16 -1 (-800 1925)(-525 1925);
WIRE 16 -1 (-4300 4200)(-4750 4200);
FORCEPROP 2 LAST SIG_NAME TP_USB_ESD_AC3
J 0
(-4735 4210);
DISPLAY 0.617021 (-4735 4210);
PAINT ORANGE (-4735 4210);
FORCEPROP 2 LASTPROP $XRERR UNIQUE?
J 0
(-4990 4200);
DISPLAY 0.638298 (-4990 4200);
PAINT MONO (-4990 4200);
DISPLAY INVISIBLE (-4990 4200);
WIRE 16 -1 (-25 1825)(-675 1825);
FORCEPROP 0 LAST SIG_NAME FM_OC0_USB_N
J 0
(-410 1835);
DISPLAY 0.617021 (-410 1835);
PAINT ORANGE (-410 1835);
WIRE 16 -1 (-675 2200)(-675 1825);
WIRE 16 -1 (-800 1825)(-675 1825);
WIRE 16 3135 (-4950 4275)(-4950 5525);
WIRE 16 3135 (-5650 4275)(-4950 4275);
WIRE 16 3135 (-4950 5525)(-5650 5525);
WIRE 16 3135 (-5650 5525)(-5650 4275);
WIRE 16 -1 (-4300 4150)(-4750 4150);
FORCEPROP 2 LAST SIG_NAME TP_USB_ESD_AC2
J 0
(-4735 4160);
DISPLAY 0.617021 (-4735 4160);
PAINT ORANGE (-4735 4160);
FORCEPROP 2 LASTPROP $XRERR UNIQUE?
J 0
(-4990 4150);
DISPLAY 0.638298 (-4990 4150);
PAINT MONO (-4990 4150);
DISPLAY INVISIBLE (-4990 4150);
DOT 1 (-50 4250);
DOT 1 (-2950 4400);
DOT 1 (-3050 4450);
DOT 1 (-1800 2450);
DOT 1 (-1850 1725);
DOT 1 (-675 1825);
DOT 1 (-525 1925);
DOT 1 (-50 4300);
DOT 1 (-2550 4250);
DOT 1 (-5550 4825);
DOT 1 (-5000 4825);
DOT 1 (-4875 4625);
DOT 1 (-4825 4825);
DOT 1 (-5000 4625);
DOT 1 (-5550 4625);
FORCENOTE
TP FAB1 ADD AND GATE TO ISOLATR RX SIGNAL 1119
(-1500 3500) 0;
DISPLAY LEFT (-1500 3500);
DISPLAY 1.021277 (-1500 3500);
PAINT RED (-1500 3500);
FORCENOTE
TP FAB1 DEL USB3.0 SIGNAL 1117
(-6425 3050) 0;
DISPLAY LEFT (-6425 3050);
DISPLAY 1.021277 (-6425 3050);
PAINT RED (-6425 3050);
FORCENOTE
TP FAB1 CHANGE NET NAME 1117
(-2450 5300) 0;
DISPLAY LEFT (-2450 5300);
DISPLAY 1.021277 (-2450 5300);
PAINT RED (-2450 5300);
FORCENOTE
ROOM=USB_REAR
(-7275 1050) 0;
DISPLAY LEFT (-7275 1050);
DISPLAY 0.808511 (-7275 1050);
PAINT PURPLE (-7275 1050);
QUIT
